(kicad_pcb
	(version 20260206)
	(generator "pcbnew")
	(generator_version "10.0")
	(general
		(thickness 1.6)
		(legacy_teardrops no)
	)
	(paper "A4")
	(title_block
		(title "Bryce Canyon_SCC_16316-1_OCP.brd")
		(comment 1 "Bryce Canyon / footprints 1355-1362 of 1561")
	)
	(layers
		(0 "F.Cu" signal "TOP")
		(4 "In1.Cu" signal "L2GND")
		(6 "In2.Cu" signal "L3")
		(8 "In3.Cu" signal "L4VCC")
		(10 "In4.Cu" signal "L5VCC")
		(12 "In5.Cu" signal "L6")
		(14 "In6.Cu" signal "L7GND")
		(2 "B.Cu" signal "BOTTOM")
		(9 "F.Adhes" user "F.Adhesive")
		(11 "B.Adhes" user "B.Adhesive")
		(13 "F.Paste" user "Package Geometry/Pastemask Top")
		(15 "B.Paste" user "Package Geometry/Pastemask Bottom")
		(5 "F.SilkS" user "Ref Des/Silkscreen Top")
		(7 "B.SilkS" user "Ref Des/Silkscreen Bottom")
		(1 "F.Mask" user "Board Geometry/Soldermask Top")
		(3 "B.Mask" user "Board Geometry/Soldermask Bottom")
		(17 "Dwgs.User" user "User.Drawings")
		(19 "Cmts.User" user "User.Comments")
		(21 "Eco1.User" user "User.Eco1")
		(23 "Eco2.User" user "User.Eco2")
		(25 "Edge.Cuts" user "Board Geometry/Outline")
		(27 "Margin" user)
		(31 "F.CrtYd" user "Package Geometry/Place Bound Top")
		(29 "B.CrtYd" user "Package Geometry/Place Bound Bottom")
		(35 "F.Fab" user "Ref Des/Assembly Top")
		(33 "B.Fab" user "Ref Des/Assembly Bottom")
	)
	(footprint ""
		(layer "B.Cu")
		(at 133.482588 -87.260684)
		(property "Reference" "R71"
			(at 0 0 0)
			(layer "B.SilkS")
			(hide yes)
			(effects
				(font
					(size 1.27 1.27)
				)
				(justify mirror)
			)
		)
		(property "Value" "1KR2F-3-GP"
			(at -0.064008 -3.993896 0)
			(unlocked yes)
			(layer "B.Fab")
			(hide yes)
			(effects
				(font
					(size 1.016 1.016)
					(thickness 0.1524)
				)
				(justify mirror)
			)
		)
		(property "Device Type" "R402H16"
			(at -0.064008 -5.517896 0)
			(unlocked yes)
			(layer "B.Fab")
			(hide yes)
			(effects
				(font
					(size 1.016 1.016)
					(thickness 0.1524)
				)
				(justify mirror)
			)
		)
		(duplicate_pad_numbers_are_jumpers no)
		(fp_line
			(start -0.508 -0.9398)
			(end 0.508 -0.9398)
			(stroke
				(width 0.1524)
				(type default)
			)
			(layer "B.SilkS")
		)
		(fp_line
			(start 0.508 -0.9398)
			(end 0.508 0.9398)
			(stroke
				(width 0.1524)
				(type default)
			)
			(layer "B.SilkS")
		)
		(fp_rect
			(start 0.508 0.9398)
			(end -0.508 -0.9398)
			(stroke
				(width 0)
				(type default)
			)
			(fill no)
			(layer "B.CrtYd")
		)
		(fp_rect
			(start 0.508 0.9398)
			(end -0.508 -0.9398)
			(stroke
				(width 0)
				(type default)
			)
			(fill no)
			(layer "B.Fab")
		)
		(pad "1" smd custom
			(at 0 -0.4445 180)
			(size 0.1397 0.1397)
			(layers "B.Cu" "B.Mask" "B.Paste")
			(net "P1V8_E")
			(options
				(clearance outline)
				(anchor circle)
			)
			(primitives
				(gr_poly
					(pts
						(arc
							(start -0.1778 0.2794)
							(mid -0.249642 0.249642)
							(end -0.2794 0.1778)
						)
						(arc
							(start -0.2794 -0.1778)
							(mid -0.249642 -0.249642)
							(end -0.1778 -0.2794)
						)
						(arc
							(start 0.1778 -0.2794)
							(mid 0.249642 -0.249642)
							(end 0.2794 -0.1778)
						)
						(arc
							(start 0.2794 0.1778)
							(mid 0.249642 0.249642)
							(end 0.1778 0.2794)
						)
					)
					(width 0)
					(fill yes)
				)
			)
		)
		(pad "2" smd custom
			(at 0 0.4445 180)
			(size 0.1397 0.1397)
			(layers "B.Cu" "B.Mask" "B.Paste")
			(net "EXP_I2C_SDA11")
			(options
				(clearance outline)
				(anchor circle)
			)
			(primitives
				(gr_poly
					(pts
						(arc
							(start -0.1778 0.2794)
							(mid -0.249642 0.249642)
							(end -0.2794 0.1778)
						)
						(arc
							(start -0.2794 -0.1778)
							(mid -0.249642 -0.249642)
							(end -0.1778 -0.2794)
						)
						(arc
							(start 0.1778 -0.2794)
							(mid 0.249642 -0.249642)
							(end 0.2794 -0.1778)
						)
						(arc
							(start 0.2794 0.1778)
							(mid 0.249642 0.249642)
							(end 0.1778 0.2794)
						)
					)
					(width 0)
					(fill yes)
				)
			)
		)
	)
	(footprint ""
		(layer "B.Cu")
		(at 103.9114 -86.9442 180)
		(property "Reference" "R567"
			(at 0 0 0)
			(layer "B.SilkS")
			(hide yes)
			(effects
				(font
					(size 1.27 1.27)
				)
				(justify mirror)
			)
		)
		(property "Value" "10KR2F-2-GP"
			(at -0.064008 -3.993896 180)
			(unlocked yes)
			(layer "B.Fab")
			(hide yes)
			(effects
				(font
					(size 1.016 1.016)
					(thickness 0.1524)
				)
				(justify mirror)
			)
		)
		(property "Device Type" "R402H16"
			(at -0.064008 -5.517896 180)
			(unlocked yes)
			(layer "B.Fab")
			(hide yes)
			(effects
				(font
					(size 1.016 1.016)
					(thickness 0.1524)
				)
				(justify mirror)
			)
		)
		(duplicate_pad_numbers_are_jumpers no)
		(fp_line
			(start 0.508 -0.9398)
			(end 0.508 0.9398)
			(stroke
				(width 0.1524)
				(type default)
			)
			(layer "B.SilkS")
		)
		(fp_line
			(start -0.508 -0.9398)
			(end 0.508 -0.9398)
			(stroke
				(width 0.1524)
				(type default)
			)
			(layer "B.SilkS")
		)
		(fp_rect
			(start 0.508 0.9398)
			(end -0.508 -0.9398)
			(stroke
				(width 0)
				(type default)
			)
			(fill no)
			(layer "B.CrtYd")
		)
		(fp_rect
			(start 0.508 0.9398)
			(end -0.508 -0.9398)
			(stroke
				(width 0)
				(type default)
			)
			(fill no)
			(layer "B.Fab")
		)
		(pad "1" smd custom
			(at 0 -0.4445)
			(size 0.1397 0.1397)
			(layers "B.Cu" "B.Mask" "B.Paste")
			(net "SYS_PWR_LED_LS_N")
			(options
				(clearance outline)
				(anchor circle)
			)
			(primitives
				(gr_poly
					(pts
						(arc
							(start -0.1778 0.2794)
							(mid -0.249642 0.249642)
							(end -0.2794 0.1778)
						)
						(arc
							(start -0.2794 -0.1778)
							(mid -0.249642 -0.249642)
							(end -0.1778 -0.2794)
						)
						(arc
							(start 0.1778 -0.2794)
							(mid 0.249642 -0.249642)
							(end 0.2794 -0.1778)
						)
						(arc
							(start 0.2794 0.1778)
							(mid 0.249642 0.249642)
							(end 0.1778 0.2794)
						)
					)
					(width 0)
					(fill yes)
				)
			)
		)
		(pad "2" smd custom
			(at 0 0.4445)
			(size 0.1397 0.1397)
			(layers "B.Cu" "B.Mask" "B.Paste")
			(net "P1V8_E")
			(options
				(clearance outline)
				(anchor circle)
			)
			(primitives
				(gr_poly
					(pts
						(arc
							(start -0.1778 0.2794)
							(mid -0.249642 0.249642)
							(end -0.2794 0.1778)
						)
						(arc
							(start -0.2794 -0.1778)
							(mid -0.249642 -0.249642)
							(end -0.1778 -0.2794)
						)
						(arc
							(start 0.1778 -0.2794)
							(mid 0.249642 -0.249642)
							(end 0.2794 -0.1778)
						)
						(arc
							(start 0.2794 0.1778)
							(mid 0.249642 0.249642)
							(end 0.1778 0.2794)
						)
					)
					(width 0)
					(fill yes)
				)
			)
		)
	)
	(footprint ""
		(layer "B.Cu")
		(at 148.209 -114.173 90)
		(property "Reference" "C674"
			(at 0 0 90)
			(layer "B.SilkS")
			(hide yes)
			(effects
				(font
					(size 1.27 1.27)
				)
				(justify mirror)
			)
		)
		(property "Value" "SCD1U16V2KX-3GP"
			(at -1.1811 -2.7051 90)
			(unlocked yes)
			(layer "B.Fab")
			(hide yes)
			(effects
				(font
					(size 1.016 1.016)
					(thickness 0.1524)
				)
				(justify mirror)
			)
		)
		(property "Device Type" "C402H22"
			(at -1.1811 -4.2291 90)
			(unlocked yes)
			(layer "B.Fab")
			(hide yes)
			(effects
				(font
					(size 1.016 1.016)
					(thickness 0.1524)
				)
				(justify mirror)
			)
		)
		(duplicate_pad_numbers_are_jumpers no)
		(fp_rect
			(start 0.4318 0.9525)
			(end -0.4318 -0.9525)
			(stroke
				(width 0)
				(type default)
			)
			(fill no)
			(layer "B.CrtYd")
		)
		(fp_rect
			(start 0.4318 0.9525)
			(end -0.4318 -0.9525)
			(stroke
				(width 0)
				(type default)
			)
			(fill no)
			(layer "B.Fab")
		)
		(pad "1" smd custom
			(at 0 -0.4445 270)
			(size 0.1524 0.1524)
			(layers "B.Cu" "B.Mask" "B.Paste")
			(net "P1V5_E_RC")
			(options
				(clearance outline)
				(anchor circle)
			)
			(primitives
				(gr_poly
					(pts
						(arc
							(start 0.3048 0.2032)
							(mid 0.275042 0.275042)
							(end 0.2032 0.3048)
						)
						(arc
							(start -0.2032 0.3048)
							(mid -0.275042 0.275042)
							(end -0.3048 0.2032)
						)
						(arc
							(start -0.3048 -0.2032)
							(mid -0.275042 -0.275042)
							(end -0.2032 -0.3048)
						)
						(arc
							(start 0.2032 -0.3048)
							(mid 0.275042 -0.275042)
							(end 0.3048 -0.2032)
						)
					)
					(width 0)
					(fill yes)
				)
			)
		)
		(pad "2" smd custom
			(at 0 0.4445 270)
			(size 0.1524 0.1524)
			(layers "B.Cu" "B.Mask" "B.Paste")
			(net "P1V5_E_LL")
			(options
				(clearance outline)
				(anchor circle)
			)
			(primitives
				(gr_poly
					(pts
						(arc
							(start 0.3048 0.2032)
							(mid 0.275042 0.275042)
							(end 0.2032 0.3048)
						)
						(arc
							(start -0.2032 0.3048)
							(mid -0.275042 0.275042)
							(end -0.3048 0.2032)
						)
						(arc
							(start -0.3048 -0.2032)
							(mid -0.275042 -0.275042)
							(end -0.2032 -0.3048)
						)
						(arc
							(start 0.2032 -0.3048)
							(mid 0.275042 -0.275042)
							(end 0.3048 -0.2032)
						)
					)
					(width 0)
					(fill yes)
				)
			)
		)
	)
	(footprint ""
		(layer "B.Cu")
		(at 104.648 -67.056)
		(property "Reference" "C210"
			(at 0 0 0)
			(layer "B.SilkS")
			(hide yes)
			(effects
				(font
					(size 1.27 1.27)
				)
				(justify mirror)
			)
		)
		(property "Value" "SC1U6D3V1MX-GP"
			(at -1.9177 2.0193 0)
			(unlocked yes)
			(layer "B.Fab")
			(hide yes)
			(effects
				(font
					(size 1.016 1.016)
					(thickness 0.1524)
				)
				(justify mirror)
			)
		)
		(property "Device Type" "C0201H14"
			(at -1.9177 0.4953 0)
			(unlocked yes)
			(layer "B.Fab")
			(hide yes)
			(effects
				(font
					(size 1.016 1.016)
					(thickness 0.1524)
				)
				(justify mirror)
			)
		)
		(duplicate_pad_numbers_are_jumpers no)
		(fp_rect
			(start 0.1524 0.3048)
			(end -0.1524 -0.3048)
			(stroke
				(width 0)
				(type default)
			)
			(fill no)
			(layer "B.CrtYd")
		)
		(fp_poly
			(pts
				(xy 0.2794 0.6477) (xy 0.2794 -0.6477) (xy -0.2794 -0.6477) (xy -0.2794 -0.1905) (xy -0.1524 -0.1905)
				(xy -0.1524 -0.3048) (xy 0.1524 -0.3048) (xy 0.1524 0.3048) (xy -0.1524 0.3048) (xy -0.1524 -0.1778)
				(xy -0.2794 -0.1778) (xy -0.2794 0.6477)
			)
			(stroke
				(width 0)
				(type default)
			)
			(fill no)
			(layer "B.CrtYd")
		)
		(fp_rect
			(start 0.2794 0.6477)
			(end -0.2794 -0.6477)
			(stroke
				(width 0)
				(type default)
			)
			(fill no)
			(layer "B.Fab")
		)
		(pad "1" smd custom
			(at 0 -0.2794 180)
			(size 0.0762 0.0762)
			(layers "B.Cu" "B.Mask" "B.Paste")
			(net "SYSPLL_VDDA09")
			(options
				(clearance outline)
				(anchor circle)
			)
			(primitives
				(gr_poly
					(pts
						(arc
							(start 0.1524 0.127)
							(mid 0.137521 0.162921)
							(end 0.1016 0.1778)
						)
						(arc
							(start -0.1016 0.1778)
							(mid -0.137521 0.162921)
							(end -0.1524 0.127)
						)
						(arc
							(start -0.1524 -0.127)
							(mid -0.137521 -0.162921)
							(end -0.1016 -0.1778)
						)
						(arc
							(start 0.1016 -0.1778)
							(mid 0.137521 -0.162921)
							(end 0.1524 -0.127)
						)
					)
					(width 0)
					(fill yes)
				)
			)
		)
		(pad "2" smd custom
			(at 0 0.2794 180)
			(size 0.0762 0.0762)
			(layers "B.Cu" "B.Mask" "B.Paste")
			(net "GND")
			(options
				(clearance outline)
				(anchor circle)
			)
			(primitives
				(gr_poly
					(pts
						(arc
							(start 0.1524 0.127)
							(mid 0.137521 0.162921)
							(end 0.1016 0.1778)
						)
						(arc
							(start -0.1016 0.1778)
							(mid -0.137521 0.162921)
							(end -0.1524 0.127)
						)
						(arc
							(start -0.1524 -0.127)
							(mid -0.137521 -0.162921)
							(end -0.1016 -0.1778)
						)
						(arc
							(start 0.1016 -0.1778)
							(mid 0.137521 -0.162921)
							(end 0.1524 -0.127)
						)
					)
					(width 0)
					(fill yes)
				)
			)
		)
	)
	(footprint ""
		(layer "B.Cu")
		(at 117.0178 -44.2214 180)
		(property "Reference" "C61"
			(at 0 0 0)
			(layer "B.SilkS")
			(hide yes)
			(effects
				(font
					(size 1.27 1.27)
				)
				(justify mirror)
			)
		)
		(property "Value" "SCD01U16V1KX-GP"
			(at 2.8321 -1.7399 180)
			(unlocked yes)
			(layer "B.Fab")
			(hide yes)
			(effects
				(font
					(size 1.016 1.016)
					(thickness 0.1524)
				)
				(justify mirror)
			)
		)
		(property "Device Type" "C0201H13"
			(at 2.8321 -3.2639 180)
			(unlocked yes)
			(layer "B.Fab")
			(hide yes)
			(effects
				(font
					(size 1.016 1.016)
					(thickness 0.1524)
				)
				(justify mirror)
			)
		)
		(duplicate_pad_numbers_are_jumpers no)
		(fp_rect
			(start 0.2794 0.6477)
			(end -0.2794 -0.6477)
			(stroke
				(width 0)
				(type default)
			)
			(fill no)
			(layer "B.CrtYd")
		)
		(fp_rect
			(start 0.2794 0.6477)
			(end -0.2794 -0.6477)
			(stroke
				(width 0)
				(type default)
			)
			(fill no)
			(layer "B.Fab")
		)
		(pad "1" smd custom
			(at 0 -0.2794)
			(size 0.0762 0.0762)
			(layers "B.Cu" "B.Mask" "B.Paste")
			(net "PHY_DPB_TO_SCC_33_DP")
			(options
				(clearance outline)
				(anchor circle)
			)
			(primitives
				(gr_poly
					(pts
						(arc
							(start 0.1524 0.127)
							(mid 0.137521 0.162921)
							(end 0.1016 0.1778)
						)
						(arc
							(start -0.1016 0.1778)
							(mid -0.137521 0.162921)
							(end -0.1524 0.127)
						)
						(arc
							(start -0.1524 -0.127)
							(mid -0.137521 -0.162921)
							(end -0.1016 -0.1778)
						)
						(arc
							(start 0.1016 -0.1778)
							(mid 0.137521 -0.162921)
							(end 0.1524 -0.127)
						)
					)
					(width 0)
					(fill yes)
				)
			)
		)
		(pad "2" smd custom
			(at 0 0.2794)
			(size 0.0762 0.0762)
			(layers "B.Cu" "B.Mask" "B.Paste")
			(net "PHY_DPB_TO_SCC_C_33_DP")
			(options
				(clearance outline)
				(anchor circle)
			)
			(primitives
				(gr_poly
					(pts
						(arc
							(start 0.1524 0.127)
							(mid 0.137521 0.162921)
							(end 0.1016 0.1778)
						)
						(arc
							(start -0.1016 0.1778)
							(mid -0.137521 0.162921)
							(end -0.1524 0.127)
						)
						(arc
							(start -0.1524 -0.127)
							(mid -0.137521 -0.162921)
							(end -0.1016 -0.1778)
						)
						(arc
							(start 0.1016 -0.1778)
							(mid 0.137521 -0.162921)
							(end 0.1524 -0.127)
						)
					)
					(width 0)
					(fill yes)
				)
			)
		)
	)
	(footprint ""
		(layer "B.Cu")
		(at 181.2798 -28.575)
		(property "Reference" "TP146"
			(at 0 0 0)
			(layer "B.SilkS")
			(hide yes)
			(effects
				(font
					(size 1.27 1.27)
				)
				(justify mirror)
			)
		)
		(property "Value" "TPAD28-2-GP"
			(at 0.0127 -1.6637 0)
			(unlocked yes)
			(layer "B.Fab")
			(hide yes)
			(effects
				(font
					(size 1.016 1.016)
					(thickness 0.1524)
				)
				(justify mirror)
			)
		)
		(property "Device Type" "TPAD28"
			(at 0.0127 -3.1877 0)
			(unlocked yes)
			(layer "B.Fab")
			(hide yes)
			(effects
				(font
					(size 1.016 1.016)
					(thickness 0.1524)
				)
				(justify mirror)
			)
		)
		(duplicate_pad_numbers_are_jumpers no)
		(fp_poly
			(pts
				(arc
					(start 0.3556 0)
					(mid -0.3556 0)
					(end 0.3556 0)
				)
			)
			(stroke
				(width 0)
				(type default)
			)
			(fill no)
			(layer "B.CrtYd")
		)
		(fp_poly
			(pts
				(arc
					(start 0.6096 0)
					(mid -0.6096 0)
					(end 0.6096 0)
				)
			)
			(stroke
				(width 0)
				(type default)
			)
			(fill no)
			(layer "B.Fab")
		)
		(pad "1" smd circle
			(at 0 0 180)
			(size 0.7112 0.7112)
			(layers "B.Cu" "B.Mask" "B.Paste")
			(net "SPARE2")
		)
	)
	(footprint ""
		(layer "B.Cu")
		(at 113.9698 -44.2214 180)
		(property "Reference" "C65"
			(at 0 0 0)
			(layer "B.SilkS")
			(hide yes)
			(effects
				(font
					(size 1.27 1.27)
				)
				(justify mirror)
			)
		)
		(property "Value" "SCD01U16V1KX-GP"
			(at 2.8321 -1.7399 180)
			(unlocked yes)
			(layer "B.Fab")
			(hide yes)
			(effects
				(font
					(size 1.016 1.016)
					(thickness 0.1524)
				)
				(justify mirror)
			)
		)
		(property "Device Type" "C0201H13"
			(at 2.8321 -3.2639 180)
			(unlocked yes)
			(layer "B.Fab")
			(hide yes)
			(effects
				(font
					(size 1.016 1.016)
					(thickness 0.1524)
				)
				(justify mirror)
			)
		)
		(duplicate_pad_numbers_are_jumpers no)
		(fp_rect
			(start 0.2794 0.6477)
			(end -0.2794 -0.6477)
			(stroke
				(width 0)
				(type default)
			)
			(fill no)
			(layer "B.CrtYd")
		)
		(fp_rect
			(start 0.2794 0.6477)
			(end -0.2794 -0.6477)
			(stroke
				(width 0)
				(type default)
			)
			(fill no)
			(layer "B.Fab")
		)
		(pad "1" smd custom
			(at 0 -0.2794)
			(size 0.0762 0.0762)
			(layers "B.Cu" "B.Mask" "B.Paste")
			(net "PHY_DPB_TO_SCC_27_DP")
			(options
				(clearance outline)
				(anchor circle)
			)
			(primitives
				(gr_poly
					(pts
						(arc
							(start 0.1524 0.127)
							(mid 0.137521 0.162921)
							(end 0.1016 0.1778)
						)
						(arc
							(start -0.1016 0.1778)
							(mid -0.137521 0.162921)
							(end -0.1524 0.127)
						)
						(arc
							(start -0.1524 -0.127)
							(mid -0.137521 -0.162921)
							(end -0.1016 -0.1778)
						)
						(arc
							(start 0.1016 -0.1778)
							(mid 0.137521 -0.162921)
							(end 0.1524 -0.127)
						)
					)
					(width 0)
					(fill yes)
				)
			)
		)
		(pad "2" smd custom
			(at 0 0.2794)
			(size 0.0762 0.0762)
			(layers "B.Cu" "B.Mask" "B.Paste")
			(net "PHY_DPB_TO_SCC_C_27_DP")
			(options
				(clearance outline)
				(anchor circle)
			)
			(primitives
				(gr_poly
					(pts
						(arc
							(start 0.1524 0.127)
							(mid 0.137521 0.162921)
							(end 0.1016 0.1778)
						)
						(arc
							(start -0.1016 0.1778)
							(mid -0.137521 0.162921)
							(end -0.1524 0.127)
						)
						(arc
							(start -0.1524 -0.127)
							(mid -0.137521 -0.162921)
							(end -0.1016 -0.1778)
						)
						(arc
							(start 0.1016 -0.1778)
							(mid 0.137521 -0.162921)
							(end 0.1524 -0.127)
						)
					)
					(width 0)
					(fill yes)
				)
			)
		)
	)
	(footprint ""
		(layer "B.Cu")
		(at 141.605 -87.2109)
		(property "Reference" "TP20"
			(at 0 0 0)
			(layer "B.SilkS")
			(hide yes)
			(effects
				(font
					(size 1.27 1.27)
				)
				(justify mirror)
			)
		)
		(property "Value" "TPAD28-2-GP"
			(at 0.0127 -1.6637 0)
			(unlocked yes)
			(layer "B.Fab")
			(hide yes)
			(effects
				(font
					(size 1.016 1.016)
					(thickness 0.1524)
				)
				(justify mirror)
			)
		)
		(property "Device Type" "TPAD28"
			(at 0.0127 -3.1877 0)
			(unlocked yes)
			(layer "B.Fab")
			(hide yes)
			(effects
				(font
					(size 1.016 1.016)
					(thickness 0.1524)
				)
				(justify mirror)
			)
		)
		(duplicate_pad_numbers_are_jumpers no)
		(fp_poly
			(pts
				(arc
					(start 0.3556 0)
					(mid -0.3556 0)
					(end 0.3556 0)
				)
			)
			(stroke
				(width 0)
				(type default)
			)
			(fill no)
			(layer "B.CrtYd")
		)
		(fp_poly
			(pts
				(arc
					(start 0.6096 0)
					(mid -0.6096 0)
					(end 0.6096 0)
				)
			)
			(stroke
				(width 0)
				(type default)
			)
			(fill no)
			(layer "B.Fab")
		)
		(pad "1" smd circle
			(at 0 0 180)
			(size 0.7112 0.7112)
			(layers "B.Cu" "B.Mask" "B.Paste")
			(net "EXP_I2C_SDA9")
		)
	)
)
